# BASEBOARD_FAB2 (Tioga Pass) — schematic netlist excerpt (pin names and nets, part order shuffled) for the footprints in the layout excerpt that follows; sources: Cadence DE-HDL packaged netlist, KiCad conversion of Wiwynn_Tioga_Pass_MB.brd

J1G2  SCONN288_H44441004  SCONN  pkg PIP  page 79
  \12v\(1)  = P12V_NVDIMM_GHJ
  VSS(93)  = GND
  DQ(4)  = M_H_DQ<5>
  VSS(92)  = GND
  DQ(0)  = M_H_DQ<1>
  VSS(91)  = GND
  DQS9P  = M_H_DQS_DP<9>
  DQS9N  = M_H_DQS_DN<9>
  VSS(90)  = GND
  DQ(6)  = M_H_DQ<7>
  VSS(89)  = GND
  DQ(2)  = M_H_DQ<3>
  VSS(88)  = GND
  DQ(12)  = M_H_DQ<13>
  VSS(87)  = GND
  DQ(8)  = M_H_DQ<9>
  VSS(86)  = GND
  DQS10P  = M_H_DQS_DP<10>
  DQS10N  = M_H_DQS_DN<10>
  VSS(85)  = GND
  DQ(14)  = M_H_DQ<15>
  VSS(84)  = GND
  DQ(10)  = M_H_DQ<11>
  VSS(83)  = GND
  DQ(20)  = M_H_DQ<21>
  VSS(82)  = GND
  DQ(16)  = M_H_DQ<17>
  VSS(81)  = GND
  DQS11P  = M_H_DQS_DP<11>
  DQS11N  = M_H_DQS_DN<11>
  VSS(80)  = GND
  DQ(22)  = M_H_DQ<23>
  VSS(79)  = GND
  DQ(18)  = M_H_DQ<19>
  VSS(78)  = GND
  DQ(28)  = M_H_DQ<29>
  VSS(77)  = GND
  DQ(24)  = M_H_DQ<25>
  VSS(76)  = GND
  DQS12P  = M_H_DQS_DP<12>
  DQS12N  = M_H_DQS_DN<12>
  VSS(75)  = GND
  DQ(30)  = M_H_DQ<31>
  VSS(74)  = GND
  DQ(26)  = M_H_DQ<27>
  VSS(73)  = GND
  CB(4)  = M_H_ECC<5>
  VSS(72)  = GND
  CB(0)  = M_H_ECC<1>
  VSS(71)  = GND
  DQS17P  = M_H_DQS_DP<17>
  DQS17N  = M_H_DQS_DN<17>
  VSS(70)  = GND
  CB(6)  = M_H_ECC<7>
  VSS(69)  = GND
  CB(2)  = M_H_ECC<3>
  VSS(68)  = GND
  RESET_N  = M_GHJ_RST_N
  VDD(25)  = PVDDQ_GHJ
  CKE(0)  = M_H_CKE<0>
  VDD(24)  = PVDDQ_GHJ
  ACT_N  = M_H_ACT_N
  BG(0)  = M_H_BG<0>
  VDD(23)  = PVDDQ_GHJ
  A12  = M_H_MA<12>
  A9  = M_H_MA<9>
  VDD(22)  = PVDDQ_GHJ
  A8  = M_H_MA<8>
  A6  = M_H_MA<6>
  VDD(21)  = PVDDQ_GHJ
  A3  = M_H_MA<3>
  A1  = M_H_MA<1>
  VDD(20)  = PVDDQ_GHJ
  CK0P  = M_H_CLK_DP<0>
  CK0N  = M_H_CLK_DN<0>
  VDD(19)  = PVDDQ_GHJ
  VTT(1)  = PVTT_GHJ
  EVENT_N  = FM_DIMM_EVENT_COD_N
  A0  = M_H_MA<0>
  VDD(18)  = PVDDQ_GHJ
  BA(0)  = M_H_BA<0>
  A16_RAS_N  = M_H_MA<16>
  VDD(17)  = PVDDQ_GHJ
  S0_N  = M_H_CS_N<0>
  VDD(16)  = PVDDQ_GHJ
  A15_CAS_N  = M_H_MA<15>
  ODT(0)  = M_H_ODT<0>
  VDD(15)  = PVDDQ_GHJ
  S1_N  = M_H_CS_N<1>
  VDD(14)  = PVDDQ_GHJ
  ODT(1)  = M_H_ODT<1>
  VDD(13)  = PVDDQ_GHJ
  S2_N_C(0)  = M_H_CS_N<2>
  VSS(67)  = GND
  DQ(36)  = M_H_DQ<37>
  VSS(66)  = GND
  DQ(32)  = M_H_DQ<33>
  VSS(65)  = GND
  DQS13P  = M_H_DQS_DP<13>
  DQS13N  = M_H_DQS_DN<13>
  VSS(64)  = GND
  DQ(38)  = M_H_DQ<39>
  VSS(63)  = GND
  DQ(34)  = M_H_DQ<35>
  VSS(62)  = GND
  DQ(44)  = M_H_DQ<45>
  VSS(61)  = GND
  DQ(40)  = M_H_DQ<41>
  VSS(60)  = GND
  DQS14P  = M_H_DQS_DP<14>
  DQS14N  = M_H_DQS_DN<14>
  VSS(59)  = GND
  DQ(46)  = M_H_DQ<47>
  VSS(58)  = GND
  DQ(42)  = M_H_DQ<43>
  VSS(57)  = GND
  DQ(52)  = M_H_DQ<53>
  VSS(56)  = GND
  DQ(48)  = M_H_DQ<49>
  VSS(55)  = GND
  DQS15P  = M_H_DQS_DP<15>
  DQS15N  = M_H_DQS_DN<15>
  VSS(54)  = GND
  DQ(54)  = M_H_DQ<55>
  VSS(53)  = GND
  DQ(50)  = M_H_DQ<51>
  VSS(52)  = GND
  DQ(60)  = M_H_DQ<61>
  VSS(51)  = GND
  DQ(56)  = M_H_DQ<57>
  VSS(50)  = GND
  DQS16P  = M_H_DQS_DP<16>
  DQS16N  = M_H_DQS_DN<16>
  VSS(49)  = GND
  DQ(62)  = M_H_DQ<63>
  VSS(48)  = GND
  DQ(58)  = M_H_DQ<59>
  VSS(47)  = GND
  SA(0)  = GND
  SA(1)  = PVPP_GHJ
  SCL  = SMB_DDR_GHJ_VPP_SCL
  VPP(4)  = PVPP_GHJ
  VPP(3)  = PVPP_GHJ
  RFU(2)  = TP_CH_H_DIMM_H0_RFU_2
  \12v\(0)  = P12V_NVDIMM_GHJ
  VREFCA  = M_H_VREF
  VSS(46)  = GND
  DQ(5)  = M_H_DQ<4>
  VSS(45)  = GND
  DQ(1)  = M_H_DQ<0>
  VSS(44)  = GND
  DQS0N  = M_H_DQS_DN<0>
  DQS0P  = M_H_DQS_DP<0>
  VSS(43)  = GND
  DQ(7)  = M_H_DQ<6>
  VSS(42)  = GND
  DQ(3)  = M_H_DQ<2>
  VSS(41)  = GND
  DQ(13)  = M_H_DQ<12>
  VSS(40)  = GND
  DQ(9)  = M_H_DQ<8>
  VSS(39)  = GND
  DQS1N  = M_H_DQS_DN<1>
  DQS1P  = M_H_DQS_DP<1>
  VSS(38)  = GND
  DQ(15)  = M_H_DQ<14>
  VSS(37)  = GND
  DQ(11)  = M_H_DQ<10>
  VSS(36)  = GND
  DQ(21)  = M_H_DQ<20>
  VSS(35)  = GND
  DQ(17)  = M_H_DQ<16>
  VSS(34)  = GND
  DQS2N  = M_H_DQS_DN<2>
  DQS2P  = M_H_DQS_DP<2>
  VSS(33)  = GND
  DQ(23)  = M_H_DQ<22>
  VSS(32)  = GND
  DQ(19)  = M_H_DQ<18>
  VSS(31)  = GND
  DQ(29)  = M_H_DQ<28>
  VSS(30)  = GND
  DQ(25)  = M_H_DQ<24>
  VSS(29)  = GND
  DQS3N  = M_H_DQS_DN<3>
  DQS3P  = M_H_DQS_DP<3>
  VSS(28)  = GND
  DQ(31)  = M_H_DQ<30>
  VSS(27)  = GND
  DQ(27)  = M_H_DQ<26>
  VSS(26)  = GND
  CB(5)  = M_H_ECC<4>
  VSS(25)  = GND
  CB(1)  = M_H_ECC<0>
  VSS(24)  = GND
  DQS8N  = M_H_DQS_DN<8>
  DQS8P  = M_H_DQS_DP<8>
  VSS(23)  = GND
  CB(7)  = M_H_ECC<6>
  VSS(22)  = GND
  CB(3)  = M_H_ECC<2>
  VSS(21)  = GND
  CKE(1)  = M_H_CKE<1>
  VDD(12)  = PVDDQ_GHJ
  RFU(0)  = TP_CH_H_DIMM_H0_RFU_0
  VDD(11)  = PVDDQ_GHJ
  BG(1)  = M_H_BG<1>
  ALERT_N  = M_H_ALERT_N
  VDD(10)  = PVDDQ_GHJ
  A11  = M_H_MA<11>
  A7  = M_H_MA<7>
  VDD(9)  = PVDDQ_GHJ
  A5  = M_H_MA<5>
  A4  = M_H_MA<4>
  VDD(8)  = PVDDQ_GHJ
  A2  = M_H_MA<2>
  VDD(7)  = PVDDQ_GHJ
  CK1P  = M_H_CLK_DP<1>
  CK1N  = M_H_CLK_DN<1>
  VDD(6)  = PVDDQ_GHJ
  VTT(0)  = PVTT_GHJ
  PAR  = M_H_PAR
  VDD(5)  = PVDDQ_GHJ
  BA(1)  = M_H_BA<1>
  A10  = M_H_MA<10>
  VDD(4)  = PVDDQ_GHJ
  RFU(1)  = TP_CH_H_DIMM_H0_RFU_1
  A14_WE_N  = M_H_MA<14>
  VDD(3)  = PVDDQ_GHJ
  SAVE_N_NC  = FM_ADR_COMPLETE_GHJ_N
  VDD(2)  = PVDDQ_GHJ
  A13  = M_H_MA<13>
  VDD(1)  = PVDDQ_GHJ
  A17  = M_H_MA<17>
  C(2)  = M_H_C<2>
  VDD(0)  = PVDDQ_GHJ
  S3_N_C(1)  = M_H_CS_N<3>
  SA(2)  = GND
  VSS(20)  = GND
  DQ(37)  = M_H_DQ<36>
  VSS(19)  = GND
  DQ(33)  = M_H_DQ<32>
  VSS(18)  = GND
  DQS4N  = M_H_DQS_DN<4>
  DQS4P  = M_H_DQS_DP<4>
  VSS(17)  = GND
  DQ(39)  = M_H_DQ<38>
  VSS(16)  = GND
  DQ(35)  = M_H_DQ<34>
  VSS(15)  = GND
  DQ(45)  = M_H_DQ<44>
  VSS(14)  = GND
  DQ(41)  = M_H_DQ<40>
  VSS(13)  = GND
  DQS5N  = M_H_DQS_DN<5>
  DQS5P  = M_H_DQS_DP<5>
  VSS(12)  = GND
  DQ(47)  = M_H_DQ<46>
  VSS(11)  = GND
  DQ(43)  = M_H_DQ<42>
  VSS(10)  = GND
  DQ(53)  = M_H_DQ<52>
  VSS(9)  = GND
  DQ(49)  = M_H_DQ<48>
  VSS(8)  = GND
  DQS6N  = M_H_DQS_DN<6>
  DQS6P  = M_H_DQS_DP<6>
  VSS(7)  = GND
  DQ(55)  = M_H_DQ<54>
  VSS(6)  = GND
  DQ(51)  = M_H_DQ<50>
  VSS(5)  = GND
  DQ(61)  = M_H_DQ<60>
  VSS(4)  = GND
  DQ(57)  = M_H_DQ<56>
  VSS(3)  = GND
  DQS7N  = M_H_DQS_DN<7>
  DQS7P  = M_H_DQS_DP<7>
  VSS(2)  = GND
  DQ(63)  = M_H_DQ<62>
  VSS(1)  = GND
  DQ(59)  = M_H_DQ<58>
  VSS(0)  = GND
  VDDSPD  = PVPP_GHJ
  SDA  = SMB_DDR_GHJ_VPP_SDA
  VPP(1)  = PVPP_GHJ
  VPP(0)  = PVPP_GHJ
  VPP(2)  = PVPP_GHJ

(kicad_pcb
	(version 20260206)
	(generator "pcbnew")
	(generator_version "10.0")
	(general
		(thickness 1.6)
		(legacy_teardrops no)
	)
	(paper "A4")
	(title_block
		(title "Wiwynn_Tioga_Pass_MB.brd")
		(comment 1 "Tioga Pass / footprint 2141 of 4770 (J1G2), pads 250-291 of 291")
	)
	(layers
		(0 "F.Cu" signal "TOP")
		(4 "In1.Cu" signal "L2GND")
		(6 "In2.Cu" signal "L3")
		(8 "In3.Cu" signal "L4GND")
		(10 "In4.Cu" signal "L5")
		(12 "In5.Cu" signal "L6GND")
		(14 "In6.Cu" signal "L7VCC")
		(16 "In7.Cu" signal "L8VCC")
		(18 "In8.Cu" signal "L9GND")
		(20 "In9.Cu" signal "L10")
		(22 "In10.Cu" signal "L11GND")
		(24 "In11.Cu" signal "L12")
		(26 "In12.Cu" signal "L13GND")
		(2 "B.Cu" signal "BOTTOM")
		(9 "F.Adhes" user "F.Adhesive")
		(11 "B.Adhes" user "B.Adhesive")
		(13 "F.Paste" user "Package Geometry/Pastemask Top")
		(15 "B.Paste" user "Package Geometry/Pastemask Bottom")
		(5 "F.SilkS" user "Ref Des/Silkscreen Top")
		(7 "B.SilkS" user "Ref Des/Silkscreen Bottom")
		(1 "F.Mask" user "Board Geometry/Soldermask Top")
		(3 "B.Mask" user "Board Geometry/Soldermask Bottom")
		(17 "Dwgs.User" user "User.Drawings")
		(19 "Cmts.User" user "User.Comments")
		(21 "Eco1.User" user "User.Eco1")
		(23 "Eco2.User" user "User.Eco2")
		(25 "Edge.Cuts" user "Board Geometry/Outline")
		(27 "Margin" user)
		(31 "F.CrtYd" user "Package Geometry/Place Bound Top")
		(29 "B.CrtYd" user "Package Geometry/Place Bound Bottom")
		(35 "F.Fab" user "Ref Des/Assembly Top")
		(33 "B.Fab" user "Ref Des/Assembly Bottom")
	)
	(footprint ""
		(layer "F.Cu")
		(at 29.699458 -5.822442 90)
		(property "Reference" "J1G2"
			(at 7.104888 34.562542 0)
			(unlocked yes)
			(layer "F.SilkS")
			(effects
				(font
					(size 0.7874 0.5842)
					(thickness 0.1524)
				)
				(justify left)
			)
		)
		(property "Value" ""
			(at 0 0 90)
			(layer "F.Fab")
			(effects
				(font
					(size 1.27 1.27)
				)
			)
		)
		(duplicate_pad_numbers_are_jumpers no)
		(pad "247" smd rect
			(at 4.59994 91.799918 90)
			(size 1.8034 0.508)
			(layers "F.Cu" "F.Mask" "F.Paste")
			(net "M_H_DQ<38>")
		)
		(pad "248" smd rect
			(at 4.59994 92.650056 90)
			(size 1.8034 0.508)
			(layers "F.Cu" "F.Mask" "F.Paste")
			(net "GND")
		)
		(pad "249" smd rect
			(at 4.59994 93.49994 90)
			(size 1.8034 0.508)
			(layers "F.Cu" "F.Mask" "F.Paste")
			(net "M_H_DQ<34>")
		)
		(pad "250" smd rect
			(at 4.59994 94.350078 90)
			(size 1.8034 0.508)
			(layers "F.Cu" "F.Mask" "F.Paste")
			(net "GND")
		)
		(pad "251" smd rect
			(at 4.59994 95.199962 90)
			(size 1.8034 0.508)
			(layers "F.Cu" "F.Mask" "F.Paste")
			(net "M_H_DQ<44>")
		)
		(pad "252" smd rect
			(at 4.59994 96.0501 90)
			(size 1.8034 0.508)
			(layers "F.Cu" "F.Mask" "F.Paste")
			(net "GND")
		)
		(pad "253" smd rect
			(at 4.59994 96.899984 90)
			(size 1.8034 0.508)
			(layers "F.Cu" "F.Mask" "F.Paste")
			(net "M_H_DQ<40>")
		)
		(pad "254" smd rect
			(at 4.59994 97.750122 90)
			(size 1.8034 0.508)
			(layers "F.Cu" "F.Mask" "F.Paste")
			(net "GND")
		)
		(pad "255" smd rect
			(at 4.59994 98.600006 90)
			(size 1.8034 0.508)
			(layers "F.Cu" "F.Mask" "F.Paste")
			(net "M_H_DQS_DN<5>")
		)
		(pad "256" smd rect
			(at 4.59994 99.44989 90)
			(size 1.8034 0.508)
			(layers "F.Cu" "F.Mask" "F.Paste")
			(net "M_H_DQS_DP<5>")
		)
		(pad "257" smd rect
			(at 4.59994 100.300028 90)
			(size 1.8034 0.508)
			(layers "F.Cu" "F.Mask" "F.Paste")
			(net "GND")
		)
		(pad "258" smd rect
			(at 4.59994 101.149912 90)
			(size 1.8034 0.508)
			(layers "F.Cu" "F.Mask" "F.Paste")
			(net "M_H_DQ<46>")
		)
		(pad "259" smd rect
			(at 4.59994 102.00005 90)
			(size 1.8034 0.508)
			(layers "F.Cu" "F.Mask" "F.Paste")
			(net "GND")
		)
		(pad "260" smd rect
			(at 4.59994 102.849934 90)
			(size 1.8034 0.508)
			(layers "F.Cu" "F.Mask" "F.Paste")
			(net "M_H_DQ<42>")
		)
		(pad "261" smd rect
			(at 4.59994 103.700072 90)
			(size 1.8034 0.508)
			(layers "F.Cu" "F.Mask" "F.Paste")
			(net "GND")
		)
		(pad "262" smd rect
			(at 4.59994 104.549956 90)
			(size 1.8034 0.508)
			(layers "F.Cu" "F.Mask" "F.Paste")
			(net "M_H_DQ<52>")
		)
		(pad "263" smd rect
			(at 4.59994 105.400094 90)
			(size 1.8034 0.508)
			(layers "F.Cu" "F.Mask" "F.Paste")
			(net "GND")
		)
		(pad "264" smd rect
			(at 4.59994 106.249978 90)
			(size 1.8034 0.508)
			(layers "F.Cu" "F.Mask" "F.Paste")
			(net "M_H_DQ<48>")
		)
		(pad "265" smd rect
			(at 4.59994 107.100116 90)
			(size 1.8034 0.508)
			(layers "F.Cu" "F.Mask" "F.Paste")
			(net "GND")
		)
		(pad "266" smd rect
			(at 4.59994 107.95 90)
			(size 1.8034 0.508)
			(layers "F.Cu" "F.Mask" "F.Paste")
			(net "M_H_DQS_DN<6>")
		)
		(pad "267" smd rect
			(at 4.59994 108.799884 90)
			(size 1.8034 0.508)
			(layers "F.Cu" "F.Mask" "F.Paste")
			(net "M_H_DQS_DP<6>")
		)
		(pad "268" smd rect
			(at 4.59994 109.650022 90)
			(size 1.8034 0.508)
			(layers "F.Cu" "F.Mask" "F.Paste")
			(net "GND")
		)
		(pad "269" smd rect
			(at 4.59994 110.499906 90)
			(size 1.8034 0.508)
			(layers "F.Cu" "F.Mask" "F.Paste")
			(net "M_H_DQ<54>")
		)
		(pad "270" smd rect
			(at 4.59994 111.350044 90)
			(size 1.8034 0.508)
			(layers "F.Cu" "F.Mask" "F.Paste")
			(net "GND")
		)
		(pad "271" smd rect
			(at 4.59994 112.199928 90)
			(size 1.8034 0.508)
			(layers "F.Cu" "F.Mask" "F.Paste")
			(net "M_H_DQ<50>")
		)
		(pad "272" smd rect
			(at 4.59994 113.050066 90)
			(size 1.8034 0.508)
			(layers "F.Cu" "F.Mask" "F.Paste")
			(net "GND")
		)
		(pad "273" smd rect
			(at 4.59994 113.89995 90)
			(size 1.8034 0.508)
			(layers "F.Cu" "F.Mask" "F.Paste")
			(net "M_H_DQ<60>")
		)
		(pad "274" smd rect
			(at 4.59994 114.750088 90)
			(size 1.8034 0.508)
			(layers "F.Cu" "F.Mask" "F.Paste")
			(net "GND")
		)
		(pad "275" smd rect
			(at 4.59994 115.599972 90)
			(size 1.8034 0.508)
			(layers "F.Cu" "F.Mask" "F.Paste")
			(net "M_H_DQ<56>")
		)
		(pad "276" smd rect
			(at 4.59994 116.45011 90)
			(size 1.8034 0.508)
			(layers "F.Cu" "F.Mask" "F.Paste")
			(net "GND")
		)
		(pad "277" smd rect
			(at 4.59994 117.299994 90)
			(size 1.8034 0.508)
			(layers "F.Cu" "F.Mask" "F.Paste")
			(net "M_H_DQS_DN<7>")
		)
		(pad "278" smd rect
			(at 4.59994 118.149878 90)
			(size 1.8034 0.508)
			(layers "F.Cu" "F.Mask" "F.Paste")
			(net "M_H_DQS_DP<7>")
		)
		(pad "279" smd rect
			(at 4.59994 119.000016 90)
			(size 1.8034 0.508)
			(layers "F.Cu" "F.Mask" "F.Paste")
			(net "GND")
		)
		(pad "280" smd rect
			(at 4.59994 119.8499 90)
			(size 1.8034 0.508)
			(layers "F.Cu" "F.Mask" "F.Paste")
			(net "M_H_DQ<62>")
		)
		(pad "281" smd rect
			(at 4.59994 120.700038 90)
			(size 1.8034 0.508)
			(layers "F.Cu" "F.Mask" "F.Paste")
			(net "GND")
		)
		(pad "282" smd rect
			(at 4.59994 121.549922 90)
			(size 1.8034 0.508)
			(layers "F.Cu" "F.Mask" "F.Paste")
			(net "M_H_DQ<58>")
		)
		(pad "283" smd rect
			(at 4.59994 122.40006 90)
			(size 1.8034 0.508)
			(layers "F.Cu" "F.Mask" "F.Paste")
			(net "GND")
		)
		(pad "284" smd rect
			(at 4.59994 123.249944 90)
			(size 1.8034 0.508)
			(layers "F.Cu" "F.Mask" "F.Paste")
			(net "PVPP_GHJ")
		)
		(pad "285" smd rect
			(at 4.59994 124.100082 90)
			(size 1.8034 0.508)
			(layers "F.Cu" "F.Mask" "F.Paste")
			(net "SMB_DDR_GHJ_VPP_SDA")
		)
		(pad "286" smd rect
			(at 4.59994 124.949966 90)
			(size 1.8034 0.508)
			(layers "F.Cu" "F.Mask" "F.Paste")
			(net "PVPP_GHJ")
		)
		(pad "287" smd rect
			(at 4.59994 125.800104 90)
			(size 1.8034 0.508)
			(layers "F.Cu" "F.Mask" "F.Paste")
			(net "PVPP_GHJ")
		)
		(pad "288" smd rect
			(at 4.59994 126.649988 90)
			(size 1.8034 0.508)
			(layers "F.Cu" "F.Mask" "F.Paste")
			(net "PVPP_GHJ")
		)
	)
)
